(kicad_pcb
	(version 20260206)
	(generator "pcbnew")
	(generator_version "10.0")
	(general
		(thickness 1.6)
		(legacy_teardrops no)
	)
	(paper "A4")
	(title_block
		(title "Wiwynn_Tioga_Pass_MB.brd")
		(comment 1 "Tioga Pass / footprints 2476-2482 of 4770")
	)
	(layers
		(0 "F.Cu" signal "TOP")
		(4 "In1.Cu" signal "L2GND")
		(6 "In2.Cu" signal "L3")
		(8 "In3.Cu" signal "L4GND")
		(10 "In4.Cu" signal "L5")
		(12 "In5.Cu" signal "L6GND")
		(14 "In6.Cu" signal "L7VCC")
		(16 "In7.Cu" signal "L8VCC")
		(18 "In8.Cu" signal "L9GND")
		(20 "In9.Cu" signal "L10")
		(22 "In10.Cu" signal "L11GND")
		(24 "In11.Cu" signal "L12")
		(26 "In12.Cu" signal "L13GND")
		(2 "B.Cu" signal "BOTTOM")
		(9 "F.Adhes" user "F.Adhesive")
		(11 "B.Adhes" user "B.Adhesive")
		(13 "F.Paste" user "Package Geometry/Pastemask Top")
		(15 "B.Paste" user "Package Geometry/Pastemask Bottom")
		(5 "F.SilkS" user "Ref Des/Silkscreen Top")
		(7 "B.SilkS" user "Ref Des/Silkscreen Bottom")
		(1 "F.Mask" user "Board Geometry/Soldermask Top")
		(3 "B.Mask" user "Board Geometry/Soldermask Bottom")
		(17 "Dwgs.User" user "User.Drawings")
		(19 "Cmts.User" user "User.Comments")
		(21 "Eco1.User" user "User.Eco1")
		(23 "Eco2.User" user "User.Eco2")
		(25 "Edge.Cuts" user "Board Geometry/Outline")
		(27 "Margin" user)
		(31 "F.CrtYd" user "Package Geometry/Place Bound Top")
		(29 "B.CrtYd" user "Package Geometry/Place Bound Bottom")
		(35 "F.Fab" user "Ref Des/Assembly Top")
		(33 "B.Fab" user "Ref Des/Assembly Bottom")
	)
	(footprint ""
		(layer "B.Cu")
		(at 385.33705 -105.45445 -90)
		(property "Reference" "C3N22"
			(at 0 0 90)
			(layer "B.SilkS")
			(hide yes)
			(effects
				(font
					(size 1.27 1.27)
				)
				(justify mirror)
			)
		)
		(property "Value" ""
			(at 0 0 90)
			(layer "B.Fab")
			(effects
				(font
					(size 1.27 1.27)
				)
				(justify mirror)
			)
		)
		(duplicate_pad_numbers_are_jumpers no)
		(fp_rect
			(start 0.2794 0.9144)
			(end -0.2794 -0.1143)
			(stroke
				(width 0)
				(type default)
			)
			(fill no)
			(layer "B.CrtYd")
		)
		(fp_line
			(start -0.2794 0.9144)
			(end 0.2794 0.9144)
			(stroke
				(width 0.1)
				(type default)
			)
			(layer "B.Fab")
		)
		(fp_line
			(start 0.2794 0.9144)
			(end 0.2794 -0.1143)
			(stroke
				(width 0.1)
				(type default)
			)
			(layer "B.Fab")
		)
		(fp_line
			(start -0.2794 -0.1143)
			(end -0.2794 0.9144)
			(stroke
				(width 0.1)
				(type default)
			)
			(layer "B.Fab")
		)
		(fp_line
			(start 0.2794 -0.1143)
			(end -0.2794 -0.1143)
			(stroke
				(width 0.1)
				(type default)
			)
			(layer "B.Fab")
		)
		(pad "1" smd custom
			(at 0 0 180)
			(size 0.10414 0.10414)
			(layers "B.Cu" "B.Mask" "B.Paste")
			(net "P1V8_PCH_STBY")
			(options
				(clearance outline)
				(anchor circle)
			)
			(primitives
				(gr_poly
					(pts
						(xy -0.20828 -0.08636) (xy -0.20828 0.08636) (xy -0.08636 0.20828) (xy 0.086614 0.20828) (xy 0.20828 0.086614)
						(xy 0.20828 -0.08636) (xy 0.08636 -0.20828) (xy -0.08636 -0.20828)
					)
					(width 0)
					(fill yes)
				)
			)
		)
		(pad "2" smd custom
			(at 0 0.8001 180)
			(size 0.10414 0.10414)
			(layers "B.Cu" "B.Mask" "B.Paste")
			(net "GND")
			(options
				(clearance outline)
				(anchor circle)
			)
			(primitives
				(gr_poly
					(pts
						(xy -0.20828 -0.08636) (xy -0.20828 0.08636) (xy -0.08636 0.20828) (xy 0.086614 0.20828) (xy 0.20828 0.086614)
						(xy 0.20828 -0.08636) (xy 0.08636 -0.20828) (xy -0.08636 -0.20828)
					)
					(width 0)
					(fill yes)
				)
			)
		)
		(zone
			(layer "B.Cu")
			(hatch none 0.5)
			(connect_pads
				(clearance 0)
			)
			(min_thickness 0.25)
			(keepout
				(tracks not_allowed)
				(vias allowed)
				(pads allowed)
				(copperpour not_allowed)
				(footprints allowed)
			)
			(placement
				(enabled no)
				(sheetname "")
			)
			(fill
				(thermal_gap 0.5)
				(thermal_bridge_width 0.5)
				(island_removal_mode 0)
			)
			(polygon
				(pts
					(xy 385.1275 -105.36682) (xy 384.7465 -105.36682) (xy 384.7465 -105.54208) (xy 385.1275 -105.542334)
				)
			)
		)
		(zone
			(layer "B.Cu")
			(hatch none 0.5)
			(connect_pads
				(clearance 0)
			)
			(min_thickness 0.25)
			(keepout
				(tracks allowed)
				(vias not_allowed)
				(pads allowed)
				(copperpour not_allowed)
				(footprints allowed)
			)
			(placement
				(enabled no)
				(sheetname "")
			)
			(fill
				(thermal_gap 0.5)
				(thermal_bridge_width 0.5)
				(island_removal_mode 0)
			)
			(polygon
				(pts
					(xy 385.1275 -105.36682) (xy 384.7465 -105.36682) (xy 384.7465 -105.54208) (xy 385.1275 -105.542334)
				)
			)
		)
	)
	(footprint ""
		(layer "B.Cu")
		(at 416.179 -22.225)
		(property "Reference" "C25W72"
			(at 0.8382 -0.67818 0)
			(unlocked yes)
			(layer "B.SilkS")
			(effects
				(font
					(size 0.4064 0.254)
					(thickness 0.1524)
				)
				(justify left mirror)
			)
		)
		(property "Value" ""
			(at 0 0 0)
			(layer "B.Fab")
			(effects
				(font
					(size 1.27 1.27)
				)
				(justify mirror)
			)
		)
		(duplicate_pad_numbers_are_jumpers no)
		(fp_poly
			(pts
				(xy -0.3048 -0.1016) (xy -0.3048 0.9906) (xy 0.3048 0.9906) (xy 0.3048 -0.1016)
			)
			(stroke
				(width 0)
				(type default)
			)
			(fill no)
			(layer "B.CrtYd")
		)
		(fp_line
			(start -0.3048 -0.1016)
			(end 0.3048 -0.1016)
			(stroke
				(width 0.1)
				(type default)
			)
			(layer "B.Fab")
		)
		(fp_line
			(start -0.3048 0.9906)
			(end -0.3048 -0.1016)
			(stroke
				(width 0.1)
				(type default)
			)
			(layer "B.Fab")
		)
		(fp_line
			(start 0.3048 -0.1016)
			(end 0.3048 0.9906)
			(stroke
				(width 0.1)
				(type default)
			)
			(layer "B.Fab")
		)
		(fp_line
			(start 0.3048 0.9906)
			(end -0.3048 0.9906)
			(stroke
				(width 0.1)
				(type default)
			)
			(layer "B.Fab")
		)
		(pad "1" smd rect
			(at 0 0 180)
			(size 0.508 0.508)
			(layers "B.Cu" "B.Mask" "B.Paste")
			(net "BMC_VGA_BLUE")
		)
		(pad "2" smd rect
			(at 0 0.889 180)
			(size 0.508 0.508)
			(layers "B.Cu" "B.Mask" "B.Paste")
			(net "GND")
		)
		(zone
			(layer "B.Cu")
			(hatch none 0.5)
			(connect_pads
				(clearance 0)
			)
			(min_thickness 0.25)
			(keepout
				(tracks allowed)
				(vias not_allowed)
				(pads allowed)
				(copperpour not_allowed)
				(footprints allowed)
			)
			(placement
				(enabled no)
				(sheetname "")
			)
			(fill
				(thermal_gap 0.5)
				(thermal_bridge_width 0.5)
				(island_removal_mode 0)
			)
			(polygon
				(pts
					(xy 416.433 -21.971) (xy 415.925 -21.971) (xy 415.925 -21.59) (xy 416.433 -21.59)
				)
			)
		)
		(zone
			(layer "B.Cu")
			(hatch none 0.5)
			(connect_pads
				(clearance 0)
			)
			(min_thickness 0.25)
			(keepout
				(tracks not_allowed)
				(vias allowed)
				(pads allowed)
				(copperpour not_allowed)
				(footprints allowed)
			)
			(placement
				(enabled no)
				(sheetname "")
			)
			(fill
				(thermal_gap 0.5)
				(thermal_bridge_width 0.5)
				(island_removal_mode 0)
			)
			(polygon
				(pts
					(xy 416.433 -21.59) (xy 415.925 -21.59) (xy 415.925 -21.971) (xy 416.433 -21.971)
				)
			)
		)
	)
	(footprint ""
		(layer "B.Cu")
		(at -1.3208 -114.1349 -90)
		(property "Reference" "C9M9"
			(at 0 0 90)
			(layer "B.SilkS")
			(hide yes)
			(effects
				(font
					(size 1.27 1.27)
				)
				(justify mirror)
			)
		)
		(property "Value" ""
			(at 0 0 90)
			(layer "B.Fab")
			(effects
				(font
					(size 1.27 1.27)
				)
				(justify mirror)
			)
		)
		(duplicate_pad_numbers_are_jumpers no)
		(fp_rect
			(start 0.3048 0.9906)
			(end -0.3048 -0.1016)
			(stroke
				(width 0)
				(type default)
			)
			(fill no)
			(layer "B.CrtYd")
		)
		(fp_line
			(start -0.3048 0.9906)
			(end -0.3048 -0.1016)
			(stroke
				(width 0.1)
				(type default)
			)
			(layer "B.Fab")
		)
		(fp_line
			(start 0.3048 0.9906)
			(end -0.3048 0.9906)
			(stroke
				(width 0.1)
				(type default)
			)
			(layer "B.Fab")
		)
		(fp_line
			(start -0.3048 -0.1016)
			(end 0.3048 -0.1016)
			(stroke
				(width 0.1)
				(type default)
			)
			(layer "B.Fab")
		)
		(fp_line
			(start 0.3048 -0.1016)
			(end 0.3048 0.9906)
			(stroke
				(width 0.1)
				(type default)
			)
			(layer "B.Fab")
		)
		(pad "1" smd rect
			(at 0 0 90)
			(size 0.508 0.508)
			(layers "B.Cu" "B.Mask" "B.Paste")
			(net "P12V_STBY")
		)
		(pad "2" smd rect
			(at 0 0.889 90)
			(size 0.508 0.508)
			(layers "B.Cu" "B.Mask" "B.Paste")
			(net "GND")
		)
		(zone
			(layer "B.Cu")
			(hatch none 0.5)
			(connect_pads
				(clearance 0)
			)
			(min_thickness 0.25)
			(keepout
				(tracks allowed)
				(vias not_allowed)
				(pads allowed)
				(copperpour not_allowed)
				(footprints allowed)
			)
			(placement
				(enabled no)
				(sheetname "")
			)
			(fill
				(thermal_gap 0.5)
				(thermal_bridge_width 0.5)
				(island_removal_mode 0)
			)
			(polygon
				(pts
					(xy -1.9558 -113.8809) (xy -1.5748 -113.8809) (xy -1.5748 -114.3889) (xy -1.9558 -114.3889)
				)
			)
		)
		(zone
			(layer "B.Cu")
			(hatch none 0.5)
			(connect_pads
				(clearance 0)
			)
			(min_thickness 0.25)
			(keepout
				(tracks not_allowed)
				(vias allowed)
				(pads allowed)
				(copperpour not_allowed)
				(footprints allowed)
			)
			(placement
				(enabled no)
				(sheetname "")
			)
			(fill
				(thermal_gap 0.5)
				(thermal_bridge_width 0.5)
				(island_removal_mode 0)
			)
			(polygon
				(pts
					(xy -1.9558 -113.8809) (xy -1.5748 -113.8809) (xy -1.5748 -114.3889) (xy -1.9558 -114.3889)
				)
			)
		)
	)
	(footprint ""
		(layer "B.Cu")
		(at 469.197944 -9.64692 180)
		(property "Reference" "R2U35"
			(at 0.8382 -0.67818 180)
			(unlocked yes)
			(layer "B.SilkS")
			(effects
				(font
					(size 0.4064 0.254)
					(thickness 0.1524)
				)
				(justify left mirror)
			)
		)
		(property "Value" ""
			(at 0 0 0)
			(layer "B.Fab")
			(effects
				(font
					(size 1.27 1.27)
				)
				(justify mirror)
			)
		)
		(duplicate_pad_numbers_are_jumpers no)
		(fp_poly
			(pts
				(xy 0.2794 -0.1016) (xy -0.2794 -0.1016) (xy -0.2794 0.9906) (xy 0.2794 0.9906)
			)
			(stroke
				(width 0)
				(type default)
			)
			(fill no)
			(layer "B.CrtYd")
		)
		(fp_line
			(start 0.2794 0.9906)
			(end -0.2794 0.9906)
			(stroke
				(width 0.1)
				(type default)
			)
			(layer "B.Fab")
		)
		(fp_line
			(start 0.2794 -0.1016)
			(end 0.2794 0.9906)
			(stroke
				(width 0.1)
				(type default)
			)
			(layer "B.Fab")
		)
		(fp_line
			(start -0.2794 0.9906)
			(end -0.2794 -0.1016)
			(stroke
				(width 0.1)
				(type default)
			)
			(layer "B.Fab")
		)
		(fp_line
			(start -0.2794 -0.1016)
			(end 0.2794 -0.1016)
			(stroke
				(width 0.1)
				(type default)
			)
			(layer "B.Fab")
		)
		(pad "1" smd rect
			(at 0 0)
			(size 0.508 0.508)
			(layers "B.Cu" "B.Mask" "B.Paste")
			(net "SMB_SLOTX24_PCH_STBY_LVC3_SDA")
		)
		(pad "2" smd rect
			(at 0 0.889)
			(size 0.508 0.508)
			(layers "B.Cu" "B.Mask" "B.Paste")
			(net "SMB_SLOTX24_STBY_LVC3_SDA_R2")
		)
		(zone
			(layer "B.Cu")
			(hatch none 0.5)
			(connect_pads
				(clearance 0)
			)
			(min_thickness 0.25)
			(keepout
				(tracks not_allowed)
				(vias allowed)
				(pads allowed)
				(copperpour not_allowed)
				(footprints allowed)
			)
			(placement
				(enabled no)
				(sheetname "")
			)
			(fill
				(thermal_gap 0.5)
				(thermal_bridge_width 0.5)
				(island_removal_mode 0)
			)
			(polygon
				(pts
					(xy 468.943944 -10.28192) (xy 469.451944 -10.28192) (xy 469.451944 -9.90092) (xy 468.943944 -9.90092)
				)
			)
		)
		(zone
			(layer "B.Cu")
			(hatch none 0.5)
			(connect_pads
				(clearance 0)
			)
			(min_thickness 0.25)
			(keepout
				(tracks allowed)
				(vias not_allowed)
				(pads allowed)
				(copperpour not_allowed)
				(footprints allowed)
			)
			(placement
				(enabled no)
				(sheetname "")
			)
			(fill
				(thermal_gap 0.5)
				(thermal_bridge_width 0.5)
				(island_removal_mode 0)
			)
			(polygon
				(pts
					(xy 468.943944 -9.90092) (xy 469.451944 -9.90092) (xy 469.451944 -10.28192) (xy 468.943944 -10.28192)
				)
			)
		)
	)
	(footprint ""
		(layer "B.Cu")
		(at 102.692454 -73.51014)
		(property "Reference" "C8P24"
			(at 0 0 0)
			(layer "B.SilkS")
			(hide yes)
			(effects
				(font
					(size 1.27 1.27)
				)
				(justify mirror)
			)
		)
		(property "Value" ""
			(at 0 0 0)
			(layer "B.Fab")
			(effects
				(font
					(size 1.27 1.27)
				)
				(justify mirror)
			)
		)
		(duplicate_pad_numbers_are_jumpers no)
		(fp_poly
			(pts
				(xy 0.7239 -0.2159) (xy -0.7239 -0.2159) (xy -0.7239 1.9939) (xy 0.7239 1.9939)
			)
			(stroke
				(width 0)
				(type default)
			)
			(fill no)
			(layer "B.CrtYd")
		)
		(fp_line
			(start -0.7239 -0.2159)
			(end 0.7239 -0.2159)
			(stroke
				(width 0.1)
				(type default)
			)
			(layer "B.Fab")
		)
		(fp_line
			(start -0.7239 1.9939)
			(end -0.7239 -0.2159)
			(stroke
				(width 0.1)
				(type default)
			)
			(layer "B.Fab")
		)
		(fp_line
			(start 0.7239 -0.2159)
			(end 0.7239 1.9939)
			(stroke
				(width 0.1)
				(type default)
			)
			(layer "B.Fab")
		)
		(fp_line
			(start 0.7239 1.9939)
			(end -0.7239 1.9939)
			(stroke
				(width 0.1)
				(type default)
			)
			(layer "B.Fab")
		)
		(pad "1" smd rect
			(at 0 0 180)
			(size 1.27 1.016)
			(layers "B.Cu" "B.Mask" "B.Paste")
			(net "PVCCIN_CPU1")
		)
		(pad "2" smd rect
			(at 0 1.778 180)
			(size 1.27 1.016)
			(layers "B.Cu" "B.Mask" "B.Paste")
			(net "GND")
		)
		(zone
			(layer "B.Cu")
			(hatch none 0.5)
			(connect_pads
				(clearance 0)
			)
			(min_thickness 0.25)
			(keepout
				(tracks not_allowed)
				(vias allowed)
				(pads allowed)
				(copperpour not_allowed)
				(footprints allowed)
			)
			(placement
				(enabled no)
				(sheetname "")
			)
			(fill
				(thermal_gap 0.5)
				(thermal_bridge_width 0.5)
				(island_removal_mode 0)
			)
			(polygon
				(pts
					(xy 103.327454 -73.00214) (xy 102.057454 -73.00214) (xy 102.057454 -72.24014) (xy 103.327454 -72.24014)
				)
			)
		)
	)
	(footprint ""
		(layer "B.Cu")
		(at 450.215 -147.8026 -90)
		(property "Reference" "R25W175"
			(at 0.8382 -0.67818 270)
			(unlocked yes)
			(layer "B.SilkS")
			(effects
				(font
					(size 0.4064 0.254)
					(thickness 0.1524)
				)
				(justify left mirror)
			)
		)
		(property "Value" ""
			(at 0 0 90)
			(layer "B.Fab")
			(effects
				(font
					(size 1.27 1.27)
				)
				(justify mirror)
			)
		)
		(duplicate_pad_numbers_are_jumpers no)
		(fp_poly
			(pts
				(xy 0.2794 -0.1016) (xy -0.2794 -0.1016) (xy -0.2794 0.9906) (xy 0.2794 0.9906)
			)
			(stroke
				(width 0)
				(type default)
			)
			(fill no)
			(layer "B.CrtYd")
		)
		(fp_line
			(start -0.2794 0.9906)
			(end -0.2794 -0.1016)
			(stroke
				(width 0.1)
				(type default)
			)
			(layer "B.Fab")
		)
		(fp_line
			(start 0.2794 0.9906)
			(end -0.2794 0.9906)
			(stroke
				(width 0.1)
				(type default)
			)
			(layer "B.Fab")
		)
		(fp_line
			(start -0.2794 -0.1016)
			(end 0.2794 -0.1016)
			(stroke
				(width 0.1)
				(type default)
			)
			(layer "B.Fab")
		)
		(fp_line
			(start 0.2794 -0.1016)
			(end 0.2794 0.9906)
			(stroke
				(width 0.1)
				(type default)
			)
			(layer "B.Fab")
		)
		(pad "1" smd rect
			(at 0 0 90)
			(size 0.508 0.508)
			(layers "B.Cu" "B.Mask" "B.Paste")
			(net "PD_GTL2014_6_B0")
		)
		(pad "2" smd rect
			(at 0 0.889 90)
			(size 0.508 0.508)
			(layers "B.Cu" "B.Mask" "B.Paste")
			(net "GND")
		)
		(zone
			(layer "B.Cu")
			(hatch none 0.5)
			(connect_pads
				(clearance 0)
			)
			(min_thickness 0.25)
			(keepout
				(tracks not_allowed)
				(vias allowed)
				(pads allowed)
				(copperpour not_allowed)
				(footprints allowed)
			)
			(placement
				(enabled no)
				(sheetname "")
			)
			(fill
				(thermal_gap 0.5)
				(thermal_bridge_width 0.5)
				(island_removal_mode 0)
			)
			(polygon
				(pts
					(xy 449.58 -147.5486) (xy 449.58 -148.0566) (xy 449.961 -148.0566) (xy 449.961 -147.5486)
				)
			)
		)
		(zone
			(layer "B.Cu")
			(hatch none 0.5)
			(connect_pads
				(clearance 0)
			)
			(min_thickness 0.25)
			(keepout
				(tracks allowed)
				(vias not_allowed)
				(pads allowed)
				(copperpour not_allowed)
				(footprints allowed)
			)
			(placement
				(enabled no)
				(sheetname "")
			)
			(fill
				(thermal_gap 0.5)
				(thermal_bridge_width 0.5)
				(island_removal_mode 0)
			)
			(polygon
				(pts
					(xy 449.961 -147.5486) (xy 449.961 -148.0566) (xy 449.58 -148.0566) (xy 449.58 -147.5486)
				)
			)
		)
	)
	(footprint ""
		(layer "B.Cu")
		(at 173.482 -74.8792)
		(property "Reference" "R6P20"
			(at 0 0 0)
			(layer "B.SilkS")
			(hide yes)
			(effects
				(font
					(size 1.27 1.27)
				)
				(justify mirror)
			)
		)
		(property "Value" ""
			(at 0 0 0)
			(layer "B.Fab")
			(effects
				(font
					(size 1.27 1.27)
				)
				(justify mirror)
			)
		)
		(duplicate_pad_numbers_are_jumpers no)
		(fp_poly
			(pts
				(xy 0.2794 -0.1016) (xy -0.2794 -0.1016) (xy -0.2794 0.9906) (xy 0.2794 0.9906)
			)
			(stroke
				(width 0)
				(type default)
			)
			(fill no)
			(layer "B.CrtYd")
		)
		(fp_line
			(start -0.2794 -0.1016)
			(end 0.2794 -0.1016)
			(stroke
				(width 0.1)
				(type default)
			)
			(layer "B.Fab")
		)
		(fp_line
			(start -0.2794 0.9906)
			(end -0.2794 -0.1016)
			(stroke
				(width 0.1)
				(type default)
			)
			(layer "B.Fab")
		)
		(fp_line
			(start 0.2794 -0.1016)
			(end 0.2794 0.9906)
			(stroke
				(width 0.1)
				(type default)
			)
			(layer "B.Fab")
		)
		(fp_line
			(start 0.2794 0.9906)
			(end -0.2794 0.9906)
			(stroke
				(width 0.1)
				(type default)
			)
			(layer "B.Fab")
		)
		(pad "1" smd rect
			(at 0 0 180)
			(size 0.508 0.508)
			(layers "B.Cu" "B.Mask" "B.Paste")
			(net "FM_DB1200_SMB_SA1")
		)
		(pad "2" smd rect
			(at 0 0.889 180)
			(size 0.508 0.508)
			(layers "B.Cu" "B.Mask" "B.Paste")
			(net "GND")
		)
		(zone
			(layer "B.Cu")
			(hatch none 0.5)
			(connect_pads
				(clearance 0)
			)
			(min_thickness 0.25)
			(keepout
				(tracks allowed)
				(vias not_allowed)
				(pads allowed)
				(copperpour not_allowed)
				(footprints allowed)
			)
			(placement
				(enabled no)
				(sheetname "")
			)
			(fill
				(thermal_gap 0.5)
				(thermal_bridge_width 0.5)
				(island_removal_mode 0)
			)
			(polygon
				(pts
					(xy 173.736 -74.6252) (xy 173.228 -74.6252) (xy 173.228 -74.2442) (xy 173.736 -74.2442)
				)
			)
		)
		(zone
			(layer "B.Cu")
			(hatch none 0.5)
			(connect_pads
				(clearance 0)
			)
			(min_thickness 0.25)
			(keepout
				(tracks not_allowed)
				(vias allowed)
				(pads allowed)
				(copperpour not_allowed)
				(footprints allowed)
			)
			(placement
				(enabled no)
				(sheetname "")
			)
			(fill
				(thermal_gap 0.5)
				(thermal_bridge_width 0.5)
				(island_removal_mode 0)
			)
			(polygon
				(pts
					(xy 173.736 -74.2442) (xy 173.228 -74.2442) (xy 173.228 -74.6252) (xy 173.736 -74.6252)
				)
			)
		)
	)
)
